(kicad_pcb
	(version 20241229)
	(generator "pcbnew")
	(generator_version "9.0")
	(general
		(thickness 1.6296)
		(legacy_teardrops no)
	)
	(paper "A3")
	(title_block
		(title "Thunderbolt to 10GbE adapter")
		(date "2026-04-21")
		(rev "1.1.0")
		(company "Antmicro Ltd")
		(comment 1 "www.antmicro.com")
		(comment 9 "footprints 497-501 of 703")
	)
	(layers
		(0 "F.Cu" signal)
		(4 "In1.Cu" signal)
		(6 "In2.Cu" signal)
		(8 "In3.Cu" signal)
		(10 "In4.Cu" signal)
		(12 "In5.Cu" signal)
		(14 "In6.Cu" signal)
		(2 "B.Cu" signal)
		(9 "F.Adhes" user "F.Adhesive")
		(11 "B.Adhes" user "B.Adhesive")
		(13 "F.Paste" user)
		(15 "B.Paste" user)
		(5 "F.SilkS" user "F.Silkscreen")
		(7 "B.SilkS" user "B.Silkscreen")
		(1 "F.Mask" user)
		(3 "B.Mask" user)
		(17 "Dwgs.User" user "User.Drawings")
		(19 "Cmts.User" user "User.Comments")
		(21 "Eco1.User" user "User.Eco1")
		(23 "Eco2.User" user "User.Eco2")
		(25 "Edge.Cuts" user)
		(27 "Margin" user)
		(31 "F.CrtYd" user "F.Courtyard")
		(29 "B.CrtYd" user "B.Courtyard")
		(35 "F.Fab" user)
		(33 "B.Fab" user)
	)
	(footprint "antmicro-footprints:C_0402_1005Metric"
		(layer "B.Cu")
		(at 155.231866 89.260117)
		(descr "Capacitor SMD 0402")
		(tags "capacitor SMD 0402")
		(property "Reference" "C203"
			(at 18.968134 10.739883 180)
			(layer "B.SilkS")
			(effects
				(font
					(size 0.7 0.7)
					(thickness 0.15)
				)
				(justify mirror)
			)
		)
		(property "Value" "C_1u_25V_0402"
			(at -1.022927 -2.155213 180)
			(layer "B.Fab")
			(effects
				(font
					(size 0.7 0.7)
					(thickness 0.15)
				)
				(justify left bottom mirror)
			)
		)
		(property "Datasheet" "https://www.murata.com/products/productdetail?partno=GRM155R61E105KE11%23"
			(at 0 0 180)
			(layer "B.Fab")
			(hide yes)
			(effects
				(font
					(size 1.27 1.27)
					(thickness 0.15)
				)
				(justify mirror)
			)
		)
		(property "Description" "SMD Multilayer Ceramic Capacitor, 1 µF, 25 V, 0402 [1005 Metric], ± 10%, X5R, GRM Series"
			(at 0 0 180)
			(layer "B.Fab")
			(hide yes)
			(effects
				(font
					(size 1.27 1.27)
					(thickness 0.15)
				)
				(justify mirror)
			)
		)
		(property "MPN" "GRM155R61E105KE11J"
			(at 0 0 0)
			(unlocked yes)
			(layer "B.Fab")
			(hide yes)
			(effects
				(font
					(size 1 1)
					(thickness 0.15)
				)
				(justify mirror)
			)
		)
		(property "Manufacturer" "Murata"
			(at 0 0 0)
			(unlocked yes)
			(layer "B.Fab")
			(hide yes)
			(effects
				(font
					(size 1 1)
					(thickness 0.15)
				)
				(justify mirror)
			)
		)
		(property "License" "Apache-2.0"
			(at 0 0 0)
			(unlocked yes)
			(layer "B.Fab")
			(hide yes)
			(effects
				(font
					(size 1 1)
					(thickness 0.15)
				)
				(justify mirror)
			)
		)
		(property "Author" "Antmicro"
			(at 0 0 0)
			(unlocked yes)
			(layer "B.Fab")
			(hide yes)
			(effects
				(font
					(size 1 1)
					(thickness 0.15)
				)
				(justify mirror)
			)
		)
		(property "Val" "1u"
			(at 0 0 0)
			(unlocked yes)
			(layer "B.Fab")
			(hide yes)
			(effects
				(font
					(size 1 1)
					(thickness 0.15)
				)
				(justify mirror)
			)
		)
		(property "Voltage" "25V"
			(at 0 0 0)
			(unlocked yes)
			(layer "B.Fab")
			(hide yes)
			(effects
				(font
					(size 1 1)
					(thickness 0.15)
				)
				(justify mirror)
			)
		)
		(property "Dielectric" "X5R"
			(at 0 0 0)
			(unlocked yes)
			(layer "B.Fab")
			(hide yes)
			(effects
				(font
					(size 1 1)
					(thickness 0.15)
				)
				(justify mirror)
			)
		)
		(sheetname "/X710-AT2 power/")
		(sheetfile "x710-at2-power.kicad_sch")
		(attr smd)
		(fp_rect
			(start -0.925 0.47)
			(end 0.925 -0.47)
			(stroke
				(width 0.05)
				(type default)
			)
			(fill no)
			(layer "B.CrtYd")
		)
		(fp_line
			(start -0.494 -0.248)
			(end -0.494 0.25)
			(stroke
				(width 0.15)
				(type solid)
			)
			(layer "B.Fab")
		)
		(fp_line
			(start -0.494 0.25)
			(end 0.504 0.25)
			(stroke
				(width 0.15)
				(type solid)
			)
			(layer "B.Fab")
		)
		(fp_line
			(start 0.504 -0.248)
			(end -0.494 -0.248)
			(stroke
				(width 0.15)
				(type solid)
			)
			(layer "B.Fab")
		)
		(fp_line
			(start 0.504 0.25)
			(end 0.504 -0.248)
			(stroke
				(width 0.15)
				(type solid)
			)
			(layer "B.Fab")
		)
		(fp_text user "License: Apache-2.0"
			(at -0.939 -5.799 180)
			(layer "B.Fab")
			(effects
				(font
					(size 0.7 0.7)
					(thickness 0.15)
				)
				(justify left bottom mirror)
			)
		)
		(fp_text user "${REFERENCE}"
			(at -0.939 -4.599 180)
			(layer "B.Fab")
			(effects
				(font
					(size 0.7 0.7)
					(thickness 0.15)
				)
				(justify left bottom mirror)
			)
		)
		(fp_text user "Author: Antmicro"
			(at -0.939 -3.399 180)
			(layer "B.Fab")
			(effects
				(font
					(size 0.7 0.7)
					(thickness 0.15)
				)
				(justify left bottom mirror)
			)
		)
		(pad "1" smd roundrect
			(at -0.48 0)
			(size 0.59 0.64)
			(layers "B.Cu" "B.Mask" "B.Paste")
			(roundrect_rratio 0.25)
			(net 23 "GND")
			(pintype "passive")
		)
		(pad "2" smd roundrect
			(at 0.48 0)
			(size 0.59 0.64)
			(layers "B.Cu" "B.Mask" "B.Paste")
			(roundrect_rratio 0.25)
			(net 18 "+1V88")
			(pintype "passive")
		)
	)
	(footprint "antmicro-footprints:C_0402_1005Metric"
		(layer "B.Cu")
		(at 151.58 146.659998 -90)
		(descr "Capacitor SMD 0402")
		(tags "capacitor SMD 0402")
		(property "Reference" "C304"
			(at 1.09 -0.42 90)
			(layer "B.SilkS")
			(effects
				(font
					(size 0.7 0.7)
					(thickness 0.15)
				)
				(justify left bottom mirror)
			)
		)
		(property "Value" "C_470p_0402"
			(at -1.022927 -2.155213 90)
			(layer "B.Fab")
			(effects
				(font
					(size 0.7 0.7)
					(thickness 0.15)
				)
				(justify left bottom mirror)
			)
		)
		(property "Datasheet" "https://www.passivecomponent.com/wp-content/uploads/datasheet/WTC_MLCC_General_Purpose.pdf"
			(at 0 0 90)
			(layer "B.Fab")
			(hide yes)
			(effects
				(font
					(size 1.27 1.27)
					(thickness 0.15)
				)
				(justify mirror)
			)
		)
		(property "Description" "SMD Multilayer Ceramic Capacitor, General Purpose, 470 pF, 25 V, 0402 [1005 Metric], ± 10%, X7R"
			(at 0 0 90)
			(layer "B.Fab")
			(hide yes)
			(effects
				(font
					(size 1.27 1.27)
					(thickness 0.15)
				)
				(justify mirror)
			)
		)
		(property "MPN" "0402B471K250CT"
			(at 0 0 270)
			(unlocked yes)
			(layer "B.Fab")
			(hide yes)
			(effects
				(font
					(size 1 1)
					(thickness 0.15)
				)
				(justify mirror)
			)
		)
		(property "Manufacturer" "Walsin"
			(at 0 0 270)
			(unlocked yes)
			(layer "B.Fab")
			(hide yes)
			(effects
				(font
					(size 1 1)
					(thickness 0.15)
				)
				(justify mirror)
			)
		)
		(property "License" "Apache-2.0"
			(at 0 0 270)
			(unlocked yes)
			(layer "B.Fab")
			(hide yes)
			(effects
				(font
					(size 1 1)
					(thickness 0.15)
				)
				(justify mirror)
			)
		)
		(property "Author" "Antmicro"
			(at 0 0 270)
			(unlocked yes)
			(layer "B.Fab")
			(hide yes)
			(effects
				(font
					(size 1 1)
					(thickness 0.15)
				)
				(justify mirror)
			)
		)
		(property "Val" "470p"
			(at 0 0 270)
			(unlocked yes)
			(layer "B.Fab")
			(hide yes)
			(effects
				(font
					(size 1 1)
					(thickness 0.15)
				)
				(justify mirror)
			)
		)
		(property "Voltage" "25V"
			(at 0 0 270)
			(unlocked yes)
			(layer "B.Fab")
			(hide yes)
			(effects
				(font
					(size 1 1)
					(thickness 0.15)
				)
				(justify mirror)
			)
		)
		(property "Dielectric" "X7R"
			(at 0 0 270)
			(unlocked yes)
			(layer "B.Fab")
			(hide yes)
			(effects
				(font
					(size 1 1)
					(thickness 0.15)
				)
				(justify mirror)
			)
		)
		(sheetname "/2xRJ45/")
		(sheetfile "2xrj45.kicad_sch")
		(attr smd)
		(fp_rect
			(start -0.925 0.47)
			(end 0.925 -0.47)
			(stroke
				(width 0.05)
				(type default)
			)
			(fill no)
			(layer "B.CrtYd")
		)
		(fp_line
			(start -0.494 0.25)
			(end 0.504 0.25)
			(stroke
				(width 0.15)
				(type solid)
			)
			(layer "B.Fab")
		)
		(fp_line
			(start 0.504 0.25)
			(end 0.504 -0.248)
			(stroke
				(width 0.15)
				(type solid)
			)
			(layer "B.Fab")
		)
		(fp_line
			(start -0.494 -0.248)
			(end -0.494 0.25)
			(stroke
				(width 0.15)
				(type solid)
			)
			(layer "B.Fab")
		)
		(fp_line
			(start 0.504 -0.248)
			(end -0.494 -0.248)
			(stroke
				(width 0.15)
				(type solid)
			)
			(layer "B.Fab")
		)
		(fp_text user "License: Apache-2.0"
			(at -0.939 -5.799 90)
			(layer "B.Fab")
			(effects
				(font
					(size 0.7 0.7)
					(thickness 0.15)
				)
				(justify left bottom mirror)
			)
		)
		(fp_text user "Author: Antmicro"
			(at -0.939 -3.399 90)
			(layer "B.Fab")
			(effects
				(font
					(size 0.7 0.7)
					(thickness 0.15)
				)
				(justify left bottom mirror)
			)
		)
		(fp_text user "${REFERENCE}"
			(at -0.939 -4.599 90)
			(layer "B.Fab")
			(effects
				(font
					(size 0.7 0.7)
					(thickness 0.15)
				)
				(justify left bottom mirror)
			)
		)
		(pad "1" smd roundrect
			(at -0.48 0 270)
			(size 0.59 0.64)
			(layers "B.Cu" "B.Mask" "B.Paste")
			(roundrect_rratio 0.25)
			(net 23 "GND")
			(pintype "passive")
		)
		(pad "2" smd roundrect
			(at 0.48 0 270)
			(size 0.59 0.64)
			(layers "B.Cu" "B.Mask" "B.Paste")
			(roundrect_rratio 0.25)
			(net 408 "Net-(J3-LED_YG_G-)")
			(pintype "passive")
		)
	)
	(footprint "antmicro-footprints:R_0402_1005Metric"
		(layer "B.Cu")
		(at 138.351932 138.558596 180)
		(descr "Resistor SMD 0402")
		(tags "resistor SMD 0402")
		(property "Reference" "R18"
			(at -19.525001 8.1 0)
			(layer "B.SilkS")
			(effects
				(font
					(size 0.7 0.7)
					(thickness 0.15)
				)
				(justify mirror)
			)
		)
		(property "Value" "R_10k_0402"
			(at -1.011843 -1.772047 0)
			(layer "B.Fab")
			(effects
				(font
					(size 0.7 0.7)
					(thickness 0.15)
				)
				(justify left bottom mirror)
			)
		)
		(property "Datasheet" "https://www.bourns.com/docs/product-datasheets/cr.pdf"
			(at 0 0 0)
			(layer "B.Fab")
			(hide yes)
			(effects
				(font
					(size 1.27 1.27)
					(thickness 0.15)
				)
				(justify mirror)
			)
		)
		(property "Description" "SMD Chip Resistor, 10 kohm, ± 1%, 62.5 mW, 0402 [1005 Metric], Thick Film, General Purpose"
			(at 0 0 0)
			(layer "B.Fab")
			(hide yes)
			(effects
				(font
					(size 1.27 1.27)
					(thickness 0.15)
				)
				(justify mirror)
			)
		)
		(property "MPN" "CR0402-FX-1002GLF"
			(at 0 0 180)
			(unlocked yes)
			(layer "B.Fab")
			(hide yes)
			(effects
				(font
					(size 1 1)
					(thickness 0.15)
				)
				(justify mirror)
			)
		)
		(property "Manufacturer" "Bourns"
			(at 0 0 180)
			(unlocked yes)
			(layer "B.Fab")
			(hide yes)
			(effects
				(font
					(size 1 1)
					(thickness 0.15)
				)
				(justify mirror)
			)
		)
		(property "License" "Apache-2.0"
			(at 0 0 180)
			(unlocked yes)
			(layer "B.Fab")
			(hide yes)
			(effects
				(font
					(size 1 1)
					(thickness 0.15)
				)
				(justify mirror)
			)
		)
		(property "Val" "10k"
			(at 0 0 180)
			(unlocked yes)
			(layer "B.Fab")
			(hide yes)
			(effects
				(font
					(size 1 1)
					(thickness 0.15)
				)
				(justify mirror)
			)
		)
		(property "Tolerance" "1%"
			(at 0 0 180)
			(unlocked yes)
			(layer "B.Fab")
			(hide yes)
			(effects
				(font
					(size 1 1)
					(thickness 0.15)
				)
				(justify mirror)
			)
		)
		(property "Author" "Antmicro"
			(at 0 0 180)
			(unlocked yes)
			(layer "B.Fab")
			(hide yes)
			(effects
				(font
					(size 1 1)
					(thickness 0.15)
				)
				(justify mirror)
			)
		)
		(sheetname "/PD and TB DC-DC/")
		(sheetfile "PD_and_TB_DC_DC.kicad_sch")
		(attr smd)
		(fp_rect
			(start -0.925 0.47)
			(end 0.925 -0.47)
			(stroke
				(width 0.05)
				(type default)
			)
			(fill no)
			(layer "B.CrtYd")
		)
		(fp_rect
			(start -0.5 0.25)
			(end 0.5 -0.25)
			(stroke
				(width 0.15)
				(type solid)
			)
			(fill no)
			(layer "B.Fab")
		)
		(fp_text user "License: Apache-2.0"
			(at -0.95 -5.169 0)
			(layer "B.Fab")
			(effects
				(font
					(size 0.7 0.7)
					(thickness 0.15)
				)
				(justify left bottom mirror)
			)
		)
		(fp_text user "Author: Antmicro"
			(at -0.95 -4.169 0)
			(layer "B.Fab")
			(effects
				(font
					(size 0.7 0.7)
					(thickness 0.15)
				)
				(justify left bottom mirror)
			)
		)
		(fp_text user "${REFERENCE}"
			(at -0.95 -3.168 0)
			(layer "B.Fab")
			(effects
				(font
					(size 0.7 0.7)
					(thickness 0.15)
				)
				(justify left bottom mirror)
			)
		)
		(pad "1" smd roundrect
			(at -0.48 0 180)
			(size 0.59 0.64)
			(layers "B.Cu" "B.Mask" "B.Paste")
			(roundrect_rratio 0.25)
			(net 304 "/PD and TB DC-DC/TPS_3V3")
			(pintype "passive")
		)
		(pad "2" smd roundrect
			(at 0.48 0 180)
			(size 0.59 0.64)
			(layers "B.Cu" "B.Mask" "B.Paste")
			(roundrect_rratio 0.25)
			(net 204 "Net-(U3-GPIO7)")
			(pintype "passive")
		)
	)
	(footprint "antmicro-footprints:R_0402_1005Metric"
		(layer "B.Cu")
		(at 117.500002 89.750001 -90)
		(descr "Resistor SMD 0402")
		(tags "resistor SMD 0402")
		(property "Reference" "R76"
			(at 5.85 -0.3 90)
			(layer "B.SilkS")
			(effects
				(font
					(size 0.7 0.7)
					(thickness 0.15)
				)
				(justify left bottom mirror)
			)
		)
		(property "Value" "R_1k_0402"
			(at -1.011843 -1.772047 90)
			(layer "B.Fab")
			(effects
				(font
					(size 0.7 0.7)
					(thickness 0.15)
				)
				(justify left bottom mirror)
			)
		)
		(property "Datasheet" "https://www.bourns.com/docs/product-datasheets/cr.pdf"
			(at 0 0 90)
			(layer "B.Fab")
			(hide yes)
			(effects
				(font
					(size 1.27 1.27)
					(thickness 0.15)
				)
				(justify mirror)
			)
		)
		(property "Description" "SMD Chip Resistor, 1 kohm, ± 1%, 63 mW, 0402 [1005 Metric], Thick Film, General Purpose"
			(at 0 0 90)
			(layer "B.Fab")
			(hide yes)
			(effects
				(font
					(size 1.27 1.27)
					(thickness 0.15)
				)
				(justify mirror)
			)
		)
		(property "MPN" "CR0402-FX-1001GLF"
			(at 0 0 270)
			(unlocked yes)
			(layer "B.Fab")
			(hide yes)
			(effects
				(font
					(size 1 1)
					(thickness 0.15)
				)
				(justify mirror)
			)
		)
		(property "Manufacturer" "Bourns"
			(at 0 0 270)
			(unlocked yes)
			(layer "B.Fab")
			(hide yes)
			(effects
				(font
					(size 1 1)
					(thickness 0.15)
				)
				(justify mirror)
			)
		)
		(property "License" "Apache-2.0"
			(at 0 0 270)
			(unlocked yes)
			(layer "B.Fab")
			(hide yes)
			(effects
				(font
					(size 1 1)
					(thickness 0.15)
				)
				(justify mirror)
			)
		)
		(property "Author" "Antmicro"
			(at 0 0 270)
			(unlocked yes)
			(layer "B.Fab")
			(hide yes)
			(effects
				(font
					(size 1 1)
					(thickness 0.15)
				)
				(justify mirror)
			)
		)
		(property "Val" "1k"
			(at 0 0 270)
			(unlocked yes)
			(layer "B.Fab")
			(hide yes)
			(effects
				(font
					(size 1 1)
					(thickness 0.15)
				)
				(justify mirror)
			)
		)
		(property "Tolerance" "1%"
			(at 0 0 270)
			(unlocked yes)
			(layer "B.Fab")
			(hide yes)
			(effects
				(font
					(size 1 1)
					(thickness 0.15)
				)
				(justify mirror)
			)
		)
		(sheetname "/TB Controller - Power/")
		(sheetfile "tb-power.kicad_sch")
		(attr smd)
		(fp_rect
			(start -0.925 0.47)
			(end 0.925 -0.47)
			(stroke
				(width 0.05)
				(type default)
			)
			(fill no)
			(layer "B.CrtYd")
		)
		(fp_rect
			(start -0.5 0.25)
			(end 0.5 -0.25)
			(stroke
				(width 0.15)
				(type solid)
			)
			(fill no)
			(layer "B.Fab")
		)
		(fp_text user "License: Apache-2.0"
			(at -0.95 -5.169 90)
			(layer "B.Fab")
			(effects
				(font
					(size 0.7 0.7)
					(thickness 0.15)
				)
				(justify left bottom mirror)
			)
		)
		(fp_text user "${REFERENCE}"
			(at -0.95 -3.168 90)
			(layer "B.Fab")
			(effects
				(font
					(size 0.7 0.7)
					(thickness 0.15)
				)
				(justify left bottom mirror)
			)
		)
		(fp_text user "Author: Antmicro"
			(at -0.95 -4.169 90)
			(layer "B.Fab")
			(effects
				(font
					(size 0.7 0.7)
					(thickness 0.15)
				)
				(justify left bottom mirror)
			)
		)
		(pad "1" smd roundrect
			(at -0.48 0 270)
			(size 0.59 0.64)
			(layers "B.Cu" "B.Mask" "B.Paste")
			(roundrect_rratio 0.25)
			(net 23 "GND")
			(pintype "passive")
		)
		(pad "2" smd roundrect
			(at 0.48 0 270)
			(size 0.59 0.64)
			(layers "B.Cu" "B.Mask" "B.Paste")
			(roundrect_rratio 0.25)
			(net 435 "Net-(R75-Pad1)")
			(pintype "passive")
		)
	)
	(footprint "antmicro-footprints:C_0402_1005Metric"
		(layer "B.Cu")
		(at 159.961866 86.905118 -150)
		(descr "Capacitor SMD 0402")
		(tags "capacitor SMD 0402")
		(property "Reference" "C187"
			(at -12.81231 -19.284696 30)
			(layer "B.SilkS")
			(effects
				(font
					(size 0.7 0.7)
					(thickness 0.15)
				)
				(justify mirror)
			)
		)
		(property "Value" "C_1u_25V_0402"
			(at -1.022927 -2.155213 30)
			(layer "B.Fab")
			(effects
				(font
					(size 0.7 0.7)
					(thickness 0.15)
				)
				(justify left bottom mirror)
			)
		)
		(property "Datasheet" "https://www.murata.com/products/productdetail?partno=GRM155R61E105KE11%23"
			(at 0 0 30)
			(layer "B.Fab")
			(hide yes)
			(effects
				(font
					(size 1.27 1.27)
					(thickness 0.15)
				)
				(justify mirror)
			)
		)
		(property "Description" "SMD Multilayer Ceramic Capacitor, 1 µF, 25 V, 0402 [1005 Metric], ± 10%, X5R, GRM Series"
			(at 0 0 30)
			(layer "B.Fab")
			(hide yes)
			(effects
				(font
					(size 1.27 1.27)
					(thickness 0.15)
				)
				(justify mirror)
			)
		)
		(property "MPN" "GRM155R61E105KE11J"
			(at 0 0 210)
			(unlocked yes)
			(layer "B.Fab")
			(hide yes)
			(effects
				(font
					(size 1 1)
					(thickness 0.15)
				)
				(justify mirror)
			)
		)
		(property "Manufacturer" "Murata"
			(at 0 0 210)
			(unlocked yes)
			(layer "B.Fab")
			(hide yes)
			(effects
				(font
					(size 1 1)
					(thickness 0.15)
				)
				(justify mirror)
			)
		)
		(property "License" "Apache-2.0"
			(at 0 0 210)
			(unlocked yes)
			(layer "B.Fab")
			(hide yes)
			(effects
				(font
					(size 1 1)
					(thickness 0.15)
				)
				(justify mirror)
			)
		)
		(property "Author" "Antmicro"
			(at 0 0 210)
			(unlocked yes)
			(layer "B.Fab")
			(hide yes)
			(effects
				(font
					(size 1 1)
					(thickness 0.15)
				)
				(justify mirror)
			)
		)
		(property "Val" "1u"
			(at 0 0 210)
			(unlocked yes)
			(layer "B.Fab")
			(hide yes)
			(effects
				(font
					(size 1 1)
					(thickness 0.15)
				)
				(justify mirror)
			)
		)
		(property "Voltage" "25V"
			(at 0 0 210)
			(unlocked yes)
			(layer "B.Fab")
			(hide yes)
			(effects
				(font
					(size 1 1)
					(thickness 0.15)
				)
				(justify mirror)
			)
		)
		(property "Dielectric" "X5R"
			(at 0 0 210)
			(unlocked yes)
			(layer "B.Fab")
			(hide yes)
			(effects
				(font
					(size 1 1)
					(thickness 0.15)
				)
				(justify mirror)
			)
		)
		(sheetname "/X710-AT2 power/")
		(sheetfile "x710-at2-power.kicad_sch")
		(attr smd)
		(fp_poly
			(pts
				(xy -0.925 0.47) (xy 0.925 0.47) (xy 0.925 -0.47) (xy -0.925 -0.47)
			)
			(stroke
				(width 0.05)
				(type default)
			)
			(fill no)
			(layer "B.CrtYd")
		)
		(fp_line
			(start 0.504 0.25)
			(end 0.504 -0.248)
			(stroke
				(width 0.15)
				(type solid)
			)
			(layer "B.Fab")
		)
		(fp_line
			(start 0.504 -0.248)
			(end -0.494001 -0.248)
			(stroke
				(width 0.15)
				(type solid)
			)
			(layer "B.Fab")
		)
		(fp_line
			(start -0.494 0.249999)
			(end 0.504 0.25)
			(stroke
				(width 0.15)
				(type solid)
			)
			(layer "B.Fab")
		)
		(fp_line
			(start -0.494001 -0.248)
			(end -0.494 0.249999)
			(stroke
				(width 0.15)
				(type solid)
			)
			(layer "B.Fab")
		)
		(fp_text user "License: Apache-2.0"
			(at -0.939 -5.799 30)
			(layer "B.Fab")
			(effects
				(font
					(size 0.7 0.7)
					(thickness 0.15)
				)
				(justify left bottom mirror)
			)
		)
		(fp_text user "Author: Antmicro"
			(at -0.939 -3.399 30)
			(layer "B.Fab")
			(effects
				(font
					(size 0.7 0.7)
					(thickness 0.15)
				)
				(justify left bottom mirror)
			)
		)
		(fp_text user "${REFERENCE}"
			(at -0.939 -4.599 30)
			(layer "B.Fab")
			(effects
				(font
					(size 0.7 0.7)
					(thickness 0.15)
				)
				(justify left bottom mirror)
			)
		)
		(pad "1" smd roundrect
			(at -0.48 0 210)
			(size 0.59 0.64)
			(layers "B.Cu" "B.Mask" "B.Paste")
			(roundrect_rratio 0.25)
			(net 23 "GND")
			(pintype "passive")
		)
		(pad "2" smd roundrect
			(at 0.48 0 210)
			(size 0.59 0.64)
			(layers "B.Cu" "B.Mask" "B.Paste")
			(roundrect_rratio 0.25)
			(net 5 "P0_AVDDL")
			(pintype "passive")
		)
	)
)
